#ISCELL
  mstr_misc dns *
  *
#ISCELL
  pure_quanta quanta_title_block_c *
  *
#ISCELL
  logical_power universal_gnd *
  page221_i1
#CELL
  pure_quanta q_res *
  page221_i10
#ISCELL
  standard offpage *
  page221_i100
#ISCELL
  standard offpage *
  page221_i101
#CELL
  pure_quanta q_res *
  page221_i102
#CELL
  pure_quanta tca9548apwr *
  page221_i103
#ISCELL
  logical_power universal_power *
  page221_i104
#ISCELL
  logical_power universal_gnd *
  page221_i105
#CELL
  pure_quanta q_cap *
  page221_i106
#ISCELL
  standard offpage *
  page221_i107
#ISCELL
  standard offpage *
  page221_i109
#ISCELL
  standard offpage *
  page221_i110
#ISCELL
  standard offpage *
  page221_i113
#ISCELL
  standard offpage *
  page221_i114
#CELL
  pure_quanta q_res *
  page221_i115
#CELL
  pure_quanta q_res *
  page221_i116
#ISCELL
  standard offpage *
  page221_i117
#ISCELL
  standard offpage *
  page221_i118
#CELL
  pure_quanta q_res *
  page221_i119
#CELL
  pure_quanta q_res *
  page221_i120
#ISCELL
  standard offpage *
  page221_i121
#ISCELL
  standard offpage *
  page221_i122
#ISCELL
  standard offpage *
  page221_i123
#ISCELL
  standard offpage *
  page221_i124
#ISCELL
  standard offpage *
  page221_i125
#ISCELL
  standard offpage *
  page221_i126
#ISCELL
  standard offpage *
  page221_i127
#ISCELL
  standard offpage *
  page221_i128
#CELL
  pure_quanta q_res *
  page221_i137
#CELL
  pure_quanta q_res *
  page221_i138
#CELL
  pure_quanta q_res *
  page221_i139
#CELL
  pure_quanta q_res *
  page221_i140
#CELL
  pure_quanta q_res *
  page221_i141
#CELL
  pure_quanta q_res *
  page221_i142
#CELL
  pure_quanta q_res *
  page221_i143
#CELL
  pure_quanta q_res *
  page221_i144
#CELL
  pure_quanta q_res *
  page221_i145
#ISCELL
  logical_power universal_power *
  page221_i146
#CELL
  pure_quanta q_res *
  page221_i147
#ISCELL
  standard offpage *
  page221_i148
#ISCELL
  logical_power universal_gnd *
  page221_i149
#CELL
  pure_quanta q_res *
  page221_i2
#CELL
  pure_quanta q_res *
  page221_i3
#ISCELL
  standard offpage *
  page221_i33
#CELL
  pure_quanta q_res *
  page221_i34
#ISCELL
  standard offpage *
  page221_i35
#ISCELL
  standard offpage *
  page221_i36
#ISCELL
  standard offpage *
  page221_i37
#ISCELL
  logical_power universal_power *
  page221_i4
#CELL
  pure_quanta q_res *
  page221_i48
#CELL
  pure_quanta q_res *
  page221_i49
#ISCELL
  logical_power universal_gnd *
  page221_i5
#CELL
  pure_quanta q_res *
  page221_i50
#CELL
  pure_quanta q_res *
  page221_i51
#CELL
  pure_quanta q_res *
  page221_i52
#CELL
  pure_quanta q_res *
  page221_i53
#ISCELL
  logical_power universal_power *
  page221_i54
#CELL
  pure_quanta q_res *
  page221_i55
#CELL
  pure_quanta q_res *
  page221_i56
#CELL
  pure_quanta q_res *
  page221_i6
#ISCELL
  logical_power universal_gnd *
  page221_i7
#ISCELL
  standard offpage *
  page221_i75
#ISCELL
  standard offpage *
  page221_i76
#ISCELL
  standard offpage *
  page221_i77
#ISCELL
  standard offpage *
  page221_i78
#ISCELL
  standard offpage *
  page221_i79
#CELL
  pure_quanta q_res *
  page221_i8
#ISCELL
  standard offpage *
  page221_i80
#ISCELL
  standard offpage *
  page221_i81
#ISCELL
  standard offpage *
  page221_i82
#ISCELL
  standard offpage *
  page221_i83
#CELL
  pure_quanta q_res *
  page221_i9
#CELL
  pure_quanta q_res *
  page221_i98
#CELL
  pure_quanta q_res *
  page221_i99
